# S9S_MB_2U (Grand Teton) — schematic netlist excerpt (pin names and nets, part order shuffled) for the footprints in the layout excerpt that follows; sources: Cadence DE-HDL packaged netlist, KiCad conversion of 03242023_DA0F0TMBIJ0_F0T_Motherboard_J_brd_V01_OCP.brd

R4080  Q_RES  10K 1% CHIP  pkg 0402LF  page 212 : A = P3V3_AUX ; B = P3V3_PWRGD_CLKGEN
R4067  Q_RES  10K 1% CHIP  pkg 0402LF  page 162 : A = P12V_AUX ; B = P3V3_OCP_2_EN_G

(kicad_pcb
	(version 20260206)
	(generator "pcbnew")
	(generator_version "10.0")
	(general
		(thickness 1.6)
		(legacy_teardrops no)
	)
	(paper "A4")
	(title_block
		(title "03242023_DA0F0TMBIJ0_F0T_Motherboard_J_brd_V01_OCP.brd")
		(comment 1 "Grand Teton / footprints 3542-3543 of 6105")
	)
	(layers
		(0 "F.Cu" signal "TOP")
		(4 "In1.Cu" signal "GND")
		(6 "In2.Cu" signal "IN1")
		(8 "In3.Cu" signal "GND1")
		(10 "In4.Cu" signal "IN2")
		(12 "In5.Cu" signal "GND2")
		(14 "In6.Cu" signal "IN3")
		(16 "In7.Cu" signal "GND3")
		(18 "In8.Cu" signal "VCC")
		(20 "In9.Cu" signal "VCC1")
		(22 "In10.Cu" signal "GND4")
		(24 "In11.Cu" signal "IN4")
		(26 "In12.Cu" signal "GND5")
		(28 "In13.Cu" signal "IN5")
		(30 "In14.Cu" signal "GND6")
		(32 "In15.Cu" signal "IN6")
		(34 "In16.Cu" signal "GND7")
		(2 "B.Cu" signal "BOTTOM")
		(9 "F.Adhes" user "F.Adhesive")
		(11 "B.Adhes" user "B.Adhesive")
		(13 "F.Paste" user "Package Geometry/Pastemask Top")
		(15 "B.Paste" user "Package Geometry/Pastemask Bottom")
		(5 "F.SilkS" user "Ref Des/Silkscreen Top")
		(7 "B.SilkS" user "Ref Des/Silkscreen Bottom")
		(1 "F.Mask" user "Board Geometry/Soldermask Top")
		(3 "B.Mask" user "Board Geometry/Soldermask Bottom")
		(17 "Dwgs.User" user "User.Drawings")
		(19 "Cmts.User" user "User.Comments")
		(21 "Eco1.User" user "User.Eco1")
		(23 "Eco2.User" user "User.Eco2")
		(25 "Edge.Cuts" user "Board Geometry/Outline")
		(27 "Margin" user)
		(31 "F.CrtYd" user "Package Geometry/Place Bound Top")
		(29 "B.CrtYd" user "Package Geometry/Place Bound Bottom")
		(35 "F.Fab" user "Ref Des/Assembly Top")
		(33 "B.Fab" user "Ref Des/Assembly Bottom")
	)
	(footprint ""
		(layer "F.Cu")
		(at 234.126278 -245.411498 90)
		(property "Reference" "R4080"
			(at 0 0 90)
			(layer "F.SilkS")
			(hide yes)
			(effects
				(font
					(size 1.27 1.27)
				)
			)
		)
		(property "Value" ""
			(at 0 0 90)
			(layer "F.Fab")
			(effects
				(font
					(size 1.27 1.27)
				)
			)
		)
		(duplicate_pad_numbers_are_jumpers no)
		(fp_line
			(start 0.7874 -0.4064)
			(end 0.7874 0.4064)
			(stroke
				(width 0.1524)
				(type default)
			)
			(layer "F.SilkS")
		)
		(fp_line
			(start -0.7874 -0.4064)
			(end 0.7874 -0.4064)
			(stroke
				(width 0.1524)
				(type default)
			)
			(layer "F.SilkS")
		)
		(fp_line
			(start 0.7874 0.4064)
			(end -0.7874 0.4064)
			(stroke
				(width 0.1524)
				(type default)
			)
			(layer "F.SilkS")
		)
		(fp_line
			(start -0.7874 0.4064)
			(end -0.7874 -0.4064)
			(stroke
				(width 0.1524)
				(type default)
			)
			(layer "F.SilkS")
		)
		(fp_line
			(start -0.12065 -0.305054)
			(end -0.12065 -0.2794)
			(stroke
				(width 0.1)
				(type default)
			)
			(layer "F.Fab")
		)
		(fp_line
			(start -0.67945 -0.305054)
			(end -0.12065 -0.305054)
			(stroke
				(width 0.1)
				(type default)
			)
			(layer "F.Fab")
		)
		(fp_line
			(start 0.67945 -0.3048)
			(end 0.67945 0.3048)
			(stroke
				(width 0.1)
				(type default)
			)
			(layer "F.Fab")
		)
		(fp_line
			(start 0.12065 -0.3048)
			(end 0.67945 -0.3048)
			(stroke
				(width 0.1)
				(type default)
			)
			(layer "F.Fab")
		)
		(fp_line
			(start 0.12065 -0.2794)
			(end 0.12065 -0.3048)
			(stroke
				(width 0.1)
				(type default)
			)
			(layer "F.Fab")
		)
		(fp_line
			(start -0.12065 -0.2794)
			(end 0.12065 -0.2794)
			(stroke
				(width 0.1)
				(type default)
			)
			(layer "F.Fab")
		)
		(fp_line
			(start 0.120396 0.2794)
			(end -0.12065 0.2794)
			(stroke
				(width 0.1)
				(type default)
			)
			(layer "F.Fab")
		)
		(fp_line
			(start -0.12065 0.2794)
			(end -0.12065 0.3048)
			(stroke
				(width 0.1)
				(type default)
			)
			(layer "F.Fab")
		)
		(fp_line
			(start 0.67945 0.3048)
			(end 0.120396 0.3048)
			(stroke
				(width 0.1)
				(type default)
			)
			(layer "F.Fab")
		)
		(fp_line
			(start 0.120396 0.3048)
			(end 0.120396 0.2794)
			(stroke
				(width 0.1)
				(type default)
			)
			(layer "F.Fab")
		)
		(fp_line
			(start -0.12065 0.3048)
			(end -0.67945 0.3048)
			(stroke
				(width 0.1)
				(type default)
			)
			(layer "F.Fab")
		)
		(fp_line
			(start -0.67945 0.3048)
			(end -0.67945 -0.305054)
			(stroke
				(width 0.1)
				(type default)
			)
			(layer "F.Fab")
		)
		(pad "1" smd circle
			(at -0.40005 0 90)
			(size 0 0)
			(layers "F.Cu" "F.Mask" "F.Paste")
			(net "P3V3_AUX")
		)
		(pad "2" smd circle
			(at 0.40005 0 90)
			(size 0 0)
			(layers "F.Cu" "F.Mask" "F.Paste")
			(net "P3V3_PWRGD_CLKGEN")
		)
	)
	(footprint ""
		(layer "F.Cu")
		(at 64.708024 -40.208708 90)
		(property "Reference" "R4067"
			(at 0 0 90)
			(layer "F.SilkS")
			(hide yes)
			(effects
				(font
					(size 1.27 1.27)
				)
			)
		)
		(property "Value" ""
			(at 0 0 90)
			(layer "F.Fab")
			(effects
				(font
					(size 1.27 1.27)
				)
			)
		)
		(duplicate_pad_numbers_are_jumpers no)
		(fp_line
			(start 0.7874 -0.4064)
			(end 0.7874 0.4064)
			(stroke
				(width 0.1524)
				(type default)
			)
			(layer "F.SilkS")
		)
		(fp_line
			(start -0.7874 -0.4064)
			(end 0.7874 -0.4064)
			(stroke
				(width 0.1524)
				(type default)
			)
			(layer "F.SilkS")
		)
		(fp_line
			(start 0.7874 0.4064)
			(end -0.7874 0.4064)
			(stroke
				(width 0.1524)
				(type default)
			)
			(layer "F.SilkS")
		)
		(fp_line
			(start -0.7874 0.4064)
			(end -0.7874 -0.4064)
			(stroke
				(width 0.1524)
				(type default)
			)
			(layer "F.SilkS")
		)
		(fp_line
			(start -0.12065 -0.305054)
			(end -0.12065 -0.2794)
			(stroke
				(width 0.1)
				(type default)
			)
			(layer "F.Fab")
		)
		(fp_line
			(start -0.67945 -0.305054)
			(end -0.12065 -0.305054)
			(stroke
				(width 0.1)
				(type default)
			)
			(layer "F.Fab")
		)
		(fp_line
			(start 0.67945 -0.3048)
			(end 0.67945 0.3048)
			(stroke
				(width 0.1)
				(type default)
			)
			(layer "F.Fab")
		)
		(fp_line
			(start 0.12065 -0.3048)
			(end 0.67945 -0.3048)
			(stroke
				(width 0.1)
				(type default)
			)
			(layer "F.Fab")
		)
		(fp_line
			(start 0.12065 -0.2794)
			(end 0.12065 -0.3048)
			(stroke
				(width 0.1)
				(type default)
			)
			(layer "F.Fab")
		)
		(fp_line
			(start -0.12065 -0.2794)
			(end 0.12065 -0.2794)
			(stroke
				(width 0.1)
				(type default)
			)
			(layer "F.Fab")
		)
		(fp_line
			(start 0.120396 0.2794)
			(end -0.12065 0.2794)
			(stroke
				(width 0.1)
				(type default)
			)
			(layer "F.Fab")
		)
		(fp_line
			(start -0.12065 0.2794)
			(end -0.12065 0.3048)
			(stroke
				(width 0.1)
				(type default)
			)
			(layer "F.Fab")
		)
		(fp_line
			(start 0.67945 0.3048)
			(end 0.120396 0.3048)
			(stroke
				(width 0.1)
				(type default)
			)
			(layer "F.Fab")
		)
		(fp_line
			(start 0.120396 0.3048)
			(end 0.120396 0.2794)
			(stroke
				(width 0.1)
				(type default)
			)
			(layer "F.Fab")
		)
		(fp_line
			(start -0.12065 0.3048)
			(end -0.67945 0.3048)
			(stroke
				(width 0.1)
				(type default)
			)
			(layer "F.Fab")
		)
		(fp_line
			(start -0.67945 0.3048)
			(end -0.67945 -0.305054)
			(stroke
				(width 0.1)
				(type default)
			)
			(layer "F.Fab")
		)
		(pad "1" smd circle
			(at -0.40005 0 90)
			(size 0 0)
			(layers "F.Cu" "F.Mask" "F.Paste")
			(net "P12V_AUX")
		)
		(pad "2" smd circle
			(at 0.40005 0 90)
			(size 0 0)
			(layers "F.Cu" "F.Mask" "F.Paste")
			(net "P3V3_OCP_2_EN_G")
		)
	)
)
